(kicad_pcb
	(version 20260206)
	(generator "pcbnew")
	(generator_version "10.0")
	(general
		(thickness 1.6)
		(legacy_teardrops no)
	)
	(paper "A4")
	(title_block
		(title "04192023_DAF0TMB3IC0_F0TG_MB_C_brd_V02_OCP.brd")
		(comment 1 "Grand Teton / footprints 4302-4308 of 8354")
	)
	(layers
		(0 "F.Cu" signal "TOP")
		(4 "In1.Cu" signal "GND")
		(6 "In2.Cu" signal "IN1")
		(8 "In3.Cu" signal "GND1")
		(10 "In4.Cu" signal "IN2")
		(12 "In5.Cu" signal "GND2")
		(14 "In6.Cu" signal "IN3")
		(16 "In7.Cu" signal "GND3")
		(18 "In8.Cu" signal "VCC")
		(20 "In9.Cu" signal "VCC1")
		(22 "In10.Cu" signal "GND4")
		(24 "In11.Cu" signal "IN4")
		(26 "In12.Cu" signal "GND5")
		(28 "In13.Cu" signal "IN5")
		(30 "In14.Cu" signal "GND6")
		(32 "In15.Cu" signal "IN6")
		(34 "In16.Cu" signal "GND7")
		(2 "B.Cu" signal "BOTTOM")
		(9 "F.Adhes" user "F.Adhesive")
		(11 "B.Adhes" user "B.Adhesive")
		(13 "F.Paste" user "Package Geometry/Pastemask Top")
		(15 "B.Paste" user "Package Geometry/Pastemask Bottom")
		(5 "F.SilkS" user "Ref Des/Silkscreen Top")
		(7 "B.SilkS" user "Ref Des/Silkscreen Bottom")
		(1 "F.Mask" user "Board Geometry/Soldermask Top")
		(3 "B.Mask" user "Board Geometry/Soldermask Bottom")
		(17 "Dwgs.User" user "User.Drawings")
		(19 "Cmts.User" user "User.Comments")
		(21 "Eco1.User" user "User.Eco1")
		(23 "Eco2.User" user "User.Eco2")
		(25 "Edge.Cuts" user "Board Geometry/Outline")
		(27 "Margin" user)
		(31 "F.CrtYd" user "Package Geometry/Place Bound Top")
		(29 "B.CrtYd" user "Package Geometry/Place Bound Bottom")
		(35 "F.Fab" user "Ref Des/Assembly Top")
		(33 "B.Fab" user "Ref Des/Assembly Bottom")
	)
	(footprint ""
		(layer "F.Cu")
		(at 221.899988 -290.89985)
		(property "Reference" "H8"
			(at -1.960118 -4.20751 0)
			(unlocked yes)
			(layer "F.SilkS")
			(effects
				(font
					(size 0.7874 0.5842)
					(thickness 0.1524)
				)
				(justify left)
			)
		)
		(property "Value" ""
			(at 0 0 0)
			(layer "F.Fab")
			(effects
				(font
					(size 1.27 1.27)
				)
			)
		)
		(duplicate_pad_numbers_are_jumpers no)
		(pad "1" thru_hole circle
			(at 0 0)
			(size 6.1976 6.1976)
			(drill 3.7338)
			(layers "*.Cu" "*.Mask")
			(remove_unused_layers no)
			(net "GND")
			(clearance -0.9779)
			(padstack
				(mode front_inner_back)
				(layer "Inner"
					(shape circle)
					(size 5.5372 5.5372)
					(clearance -0.6477)
				)
				(layer "B.Cu"
					(shape circle)
					(size 6.1976 6.1976)
					(clearance -0.9779)
				)
			)
		)
	)
	(footprint ""
		(layer "F.Cu")
		(at 29.553662 -419.249098 -90)
		(property "Reference" "R3268"
			(at 0 0 270)
			(layer "F.SilkS")
			(hide yes)
			(effects
				(font
					(size 1.27 1.27)
				)
			)
		)
		(property "Value" ""
			(at 0 0 270)
			(layer "F.Fab")
			(effects
				(font
					(size 1.27 1.27)
				)
			)
		)
		(duplicate_pad_numbers_are_jumpers no)
		(fp_line
			(start -0.7874 0.4064)
			(end -0.7874 -0.4064)
			(stroke
				(width 0.1524)
				(type default)
			)
			(layer "F.SilkS")
		)
		(fp_line
			(start 0.7874 0.4064)
			(end -0.7874 0.4064)
			(stroke
				(width 0.1524)
				(type default)
			)
			(layer "F.SilkS")
		)
		(fp_line
			(start -0.7874 -0.4064)
			(end 0.7874 -0.4064)
			(stroke
				(width 0.1524)
				(type default)
			)
			(layer "F.SilkS")
		)
		(fp_line
			(start 0.7874 -0.4064)
			(end 0.7874 0.4064)
			(stroke
				(width 0.1524)
				(type default)
			)
			(layer "F.SilkS")
		)
		(fp_line
			(start -0.67945 0.3048)
			(end -0.67945 -0.305054)
			(stroke
				(width 0.1)
				(type default)
			)
			(layer "F.Fab")
		)
		(fp_line
			(start -0.12065 0.3048)
			(end -0.67945 0.3048)
			(stroke
				(width 0.1)
				(type default)
			)
			(layer "F.Fab")
		)
		(fp_line
			(start 0.120396 0.3048)
			(end 0.120396 0.2794)
			(stroke
				(width 0.1)
				(type default)
			)
			(layer "F.Fab")
		)
		(fp_line
			(start 0.67945 0.3048)
			(end 0.120396 0.3048)
			(stroke
				(width 0.1)
				(type default)
			)
			(layer "F.Fab")
		)
		(fp_line
			(start -0.12065 0.2794)
			(end -0.12065 0.3048)
			(stroke
				(width 0.1)
				(type default)
			)
			(layer "F.Fab")
		)
		(fp_line
			(start 0.120396 0.2794)
			(end -0.12065 0.2794)
			(stroke
				(width 0.1)
				(type default)
			)
			(layer "F.Fab")
		)
		(fp_line
			(start -0.12065 -0.2794)
			(end 0.12065 -0.2794)
			(stroke
				(width 0.1)
				(type default)
			)
			(layer "F.Fab")
		)
		(fp_line
			(start 0.12065 -0.2794)
			(end 0.12065 -0.3048)
			(stroke
				(width 0.1)
				(type default)
			)
			(layer "F.Fab")
		)
		(fp_line
			(start 0.12065 -0.3048)
			(end 0.67945 -0.3048)
			(stroke
				(width 0.1)
				(type default)
			)
			(layer "F.Fab")
		)
		(fp_line
			(start 0.67945 -0.3048)
			(end 0.67945 0.3048)
			(stroke
				(width 0.1)
				(type default)
			)
			(layer "F.Fab")
		)
		(fp_line
			(start -0.67945 -0.305054)
			(end -0.12065 -0.305054)
			(stroke
				(width 0.1)
				(type default)
			)
			(layer "F.Fab")
		)
		(fp_line
			(start -0.12065 -0.305054)
			(end -0.12065 -0.2794)
			(stroke
				(width 0.1)
				(type default)
			)
			(layer "F.Fab")
		)
		(pad "1" smd circle
			(at -0.40005 0 270)
			(size 0 0)
			(layers "F.Cu" "F.Mask" "F.Paste")
			(net "FM_P2E_EQA1")
		)
		(pad "2" smd circle
			(at 0.40005 0 270)
			(size 0 0)
			(layers "F.Cu" "F.Mask" "F.Paste")
			(net "GND")
		)
	)
	(footprint ""
		(layer "F.Cu")
		(at 20.480782 -412.850584 180)
		(property "Reference" "PR6818"
			(at 0 0 180)
			(layer "F.SilkS")
			(hide yes)
			(effects
				(font
					(size 1.27 1.27)
				)
			)
		)
		(property "Value" ""
			(at 0 0 180)
			(layer "F.Fab")
			(effects
				(font
					(size 1.27 1.27)
				)
			)
		)
		(duplicate_pad_numbers_are_jumpers no)
		(fp_line
			(start 0.7874 0.4064)
			(end -0.7874 0.4064)
			(stroke
				(width 0.1524)
				(type default)
			)
			(layer "F.SilkS")
		)
		(fp_line
			(start 0.7874 -0.4064)
			(end 0.7874 0.4064)
			(stroke
				(width 0.1524)
				(type default)
			)
			(layer "F.SilkS")
		)
		(fp_line
			(start -0.7874 0.4064)
			(end -0.7874 -0.4064)
			(stroke
				(width 0.1524)
				(type default)
			)
			(layer "F.SilkS")
		)
		(fp_line
			(start -0.7874 -0.4064)
			(end 0.7874 -0.4064)
			(stroke
				(width 0.1524)
				(type default)
			)
			(layer "F.SilkS")
		)
		(fp_line
			(start 0.67945 0.3048)
			(end 0.120396 0.3048)
			(stroke
				(width 0.1)
				(type default)
			)
			(layer "F.Fab")
		)
		(fp_line
			(start 0.67945 -0.3048)
			(end 0.67945 0.3048)
			(stroke
				(width 0.1)
				(type default)
			)
			(layer "F.Fab")
		)
		(fp_line
			(start 0.12065 -0.2794)
			(end 0.12065 -0.3048)
			(stroke
				(width 0.1)
				(type default)
			)
			(layer "F.Fab")
		)
		(fp_line
			(start 0.12065 -0.3048)
			(end 0.67945 -0.3048)
			(stroke
				(width 0.1)
				(type default)
			)
			(layer "F.Fab")
		)
		(fp_line
			(start 0.120396 0.3048)
			(end 0.120396 0.2794)
			(stroke
				(width 0.1)
				(type default)
			)
			(layer "F.Fab")
		)
		(fp_line
			(start 0.120396 0.2794)
			(end -0.12065 0.2794)
			(stroke
				(width 0.1)
				(type default)
			)
			(layer "F.Fab")
		)
		(fp_line
			(start -0.12065 0.3048)
			(end -0.67945 0.3048)
			(stroke
				(width 0.1)
				(type default)
			)
			(layer "F.Fab")
		)
		(fp_line
			(start -0.12065 0.2794)
			(end -0.12065 0.3048)
			(stroke
				(width 0.1)
				(type default)
			)
			(layer "F.Fab")
		)
		(fp_line
			(start -0.12065 -0.2794)
			(end 0.12065 -0.2794)
			(stroke
				(width 0.1)
				(type default)
			)
			(layer "F.Fab")
		)
		(fp_line
			(start -0.12065 -0.305054)
			(end -0.12065 -0.2794)
			(stroke
				(width 0.1)
				(type default)
			)
			(layer "F.Fab")
		)
		(fp_line
			(start -0.67945 0.3048)
			(end -0.67945 -0.305054)
			(stroke
				(width 0.1)
				(type default)
			)
			(layer "F.Fab")
		)
		(fp_line
			(start -0.67945 -0.305054)
			(end -0.12065 -0.305054)
			(stroke
				(width 0.1)
				(type default)
			)
			(layer "F.Fab")
		)
		(pad "1" smd circle
			(at -0.40005 0 180)
			(size 0 0)
			(layers "F.Cu" "F.Mask" "F.Paste")
			(net "P3V3_AUX")
		)
		(pad "2" smd circle
			(at 0.40005 0 180)
			(size 0 0)
			(layers "F.Cu" "F.Mask" "F.Paste")
			(net "TP_P0V9_RETIMER_CPU1_SVID_ALERT_N")
		)
	)
	(footprint ""
		(layer "F.Cu")
		(at 123.795282 -15.26667 180)
		(property "Reference" "R4192"
			(at 0 0 180)
			(layer "F.SilkS")
			(hide yes)
			(effects
				(font
					(size 1.27 1.27)
				)
			)
		)
		(property "Value" ""
			(at 0 0 180)
			(layer "F.Fab")
			(effects
				(font
					(size 1.27 1.27)
				)
			)
		)
		(duplicate_pad_numbers_are_jumpers no)
		(fp_line
			(start 0.7874 0.4064)
			(end -0.7874 0.4064)
			(stroke
				(width 0.1524)
				(type default)
			)
			(layer "F.SilkS")
		)
		(fp_line
			(start 0.7874 -0.4064)
			(end 0.7874 0.4064)
			(stroke
				(width 0.1524)
				(type default)
			)
			(layer "F.SilkS")
		)
		(fp_line
			(start -0.7874 0.4064)
			(end -0.7874 -0.4064)
			(stroke
				(width 0.1524)
				(type default)
			)
			(layer "F.SilkS")
		)
		(fp_line
			(start -0.7874 -0.4064)
			(end 0.7874 -0.4064)
			(stroke
				(width 0.1524)
				(type default)
			)
			(layer "F.SilkS")
		)
		(fp_line
			(start 0.67945 0.3048)
			(end 0.120396 0.3048)
			(stroke
				(width 0.1)
				(type default)
			)
			(layer "F.Fab")
		)
		(fp_line
			(start 0.67945 -0.3048)
			(end 0.67945 0.3048)
			(stroke
				(width 0.1)
				(type default)
			)
			(layer "F.Fab")
		)
		(fp_line
			(start 0.12065 -0.2794)
			(end 0.12065 -0.3048)
			(stroke
				(width 0.1)
				(type default)
			)
			(layer "F.Fab")
		)
		(fp_line
			(start 0.12065 -0.3048)
			(end 0.67945 -0.3048)
			(stroke
				(width 0.1)
				(type default)
			)
			(layer "F.Fab")
		)
		(fp_line
			(start 0.120396 0.3048)
			(end 0.120396 0.2794)
			(stroke
				(width 0.1)
				(type default)
			)
			(layer "F.Fab")
		)
		(fp_line
			(start 0.120396 0.2794)
			(end -0.12065 0.2794)
			(stroke
				(width 0.1)
				(type default)
			)
			(layer "F.Fab")
		)
		(fp_line
			(start -0.12065 0.3048)
			(end -0.67945 0.3048)
			(stroke
				(width 0.1)
				(type default)
			)
			(layer "F.Fab")
		)
		(fp_line
			(start -0.12065 0.2794)
			(end -0.12065 0.3048)
			(stroke
				(width 0.1)
				(type default)
			)
			(layer "F.Fab")
		)
		(fp_line
			(start -0.12065 -0.2794)
			(end 0.12065 -0.2794)
			(stroke
				(width 0.1)
				(type default)
			)
			(layer "F.Fab")
		)
		(fp_line
			(start -0.12065 -0.305054)
			(end -0.12065 -0.2794)
			(stroke
				(width 0.1)
				(type default)
			)
			(layer "F.Fab")
		)
		(fp_line
			(start -0.67945 0.3048)
			(end -0.67945 -0.305054)
			(stroke
				(width 0.1)
				(type default)
			)
			(layer "F.Fab")
		)
		(fp_line
			(start -0.67945 -0.305054)
			(end -0.12065 -0.305054)
			(stroke
				(width 0.1)
				(type default)
			)
			(layer "F.Fab")
		)
		(pad "1" smd circle
			(at -0.40005 0 180)
			(size 0 0)
			(layers "F.Cu" "F.Mask" "F.Paste")
			(net "P3V3_AUX")
		)
		(pad "2" smd circle
			(at 0.40005 0 180)
			(size 0 0)
			(layers "F.Cu" "F.Mask" "F.Paste")
			(net "U273_3_ADD1")
		)
	)
	(footprint ""
		(layer "F.Cu")
		(at 138.426952 -55.484014)
		(property "Reference" "R1659"
			(at 0 0 0)
			(layer "F.SilkS")
			(hide yes)
			(effects
				(font
					(size 1.27 1.27)
				)
			)
		)
		(property "Value" ""
			(at 0 0 0)
			(layer "F.Fab")
			(effects
				(font
					(size 1.27 1.27)
				)
			)
		)
		(duplicate_pad_numbers_are_jumpers no)
		(fp_line
			(start -0.7874 -0.4064)
			(end 0.7874 -0.4064)
			(stroke
				(width 0.1524)
				(type default)
			)
			(layer "F.SilkS")
		)
		(fp_line
			(start -0.7874 0.4064)
			(end -0.7874 -0.4064)
			(stroke
				(width 0.1524)
				(type default)
			)
			(layer "F.SilkS")
		)
		(fp_line
			(start 0.7874 -0.4064)
			(end 0.7874 0.4064)
			(stroke
				(width 0.1524)
				(type default)
			)
			(layer "F.SilkS")
		)
		(fp_line
			(start 0.7874 0.4064)
			(end -0.7874 0.4064)
			(stroke
				(width 0.1524)
				(type default)
			)
			(layer "F.SilkS")
		)
		(fp_line
			(start -0.67945 -0.305054)
			(end -0.12065 -0.305054)
			(stroke
				(width 0.1)
				(type default)
			)
			(layer "F.Fab")
		)
		(fp_line
			(start -0.67945 0.3048)
			(end -0.67945 -0.305054)
			(stroke
				(width 0.1)
				(type default)
			)
			(layer "F.Fab")
		)
		(fp_line
			(start -0.12065 -0.305054)
			(end -0.12065 -0.2794)
			(stroke
				(width 0.1)
				(type default)
			)
			(layer "F.Fab")
		)
		(fp_line
			(start -0.12065 -0.2794)
			(end 0.12065 -0.2794)
			(stroke
				(width 0.1)
				(type default)
			)
			(layer "F.Fab")
		)
		(fp_line
			(start -0.12065 0.2794)
			(end -0.12065 0.3048)
			(stroke
				(width 0.1)
				(type default)
			)
			(layer "F.Fab")
		)
		(fp_line
			(start -0.12065 0.3048)
			(end -0.67945 0.3048)
			(stroke
				(width 0.1)
				(type default)
			)
			(layer "F.Fab")
		)
		(fp_line
			(start 0.120396 0.2794)
			(end -0.12065 0.2794)
			(stroke
				(width 0.1)
				(type default)
			)
			(layer "F.Fab")
		)
		(fp_line
			(start 0.120396 0.3048)
			(end 0.120396 0.2794)
			(stroke
				(width 0.1)
				(type default)
			)
			(layer "F.Fab")
		)
		(fp_line
			(start 0.12065 -0.3048)
			(end 0.67945 -0.3048)
			(stroke
				(width 0.1)
				(type default)
			)
			(layer "F.Fab")
		)
		(fp_line
			(start 0.12065 -0.2794)
			(end 0.12065 -0.3048)
			(stroke
				(width 0.1)
				(type default)
			)
			(layer "F.Fab")
		)
		(fp_line
			(start 0.67945 -0.3048)
			(end 0.67945 0.3048)
			(stroke
				(width 0.1)
				(type default)
			)
			(layer "F.Fab")
		)
		(fp_line
			(start 0.67945 0.3048)
			(end 0.120396 0.3048)
			(stroke
				(width 0.1)
				(type default)
			)
			(layer "F.Fab")
		)
		(pad "1" smd circle
			(at -0.40005 0)
			(size 0 0)
			(layers "F.Cu" "F.Mask" "F.Paste")
			(net "P3V3_AUX")
		)
		(pad "2" smd circle
			(at 0.40005 0)
			(size 0 0)
			(layers "F.Cu" "F.Mask" "F.Paste")
			(net "SCM_JTAG_MUX_S0")
		)
	)
	(footprint ""
		(layer "F.Cu")
		(at 97.074736 -127.787654 -90)
		(property "Reference" "R1459"
			(at 0 0 270)
			(layer "F.SilkS")
			(hide yes)
			(effects
				(font
					(size 1.27 1.27)
				)
			)
		)
		(property "Value" ""
			(at 0 0 270)
			(layer "F.Fab")
			(effects
				(font
					(size 1.27 1.27)
				)
			)
		)
		(duplicate_pad_numbers_are_jumpers no)
		(fp_line
			(start -0.7874 0.4064)
			(end -0.7874 -0.4064)
			(stroke
				(width 0.1524)
				(type default)
			)
			(layer "F.SilkS")
		)
		(fp_line
			(start 0.7874 0.4064)
			(end -0.7874 0.4064)
			(stroke
				(width 0.1524)
				(type default)
			)
			(layer "F.SilkS")
		)
		(fp_line
			(start -0.7874 -0.4064)
			(end 0.7874 -0.4064)
			(stroke
				(width 0.1524)
				(type default)
			)
			(layer "F.SilkS")
		)
		(fp_line
			(start 0.7874 -0.4064)
			(end 0.7874 0.4064)
			(stroke
				(width 0.1524)
				(type default)
			)
			(layer "F.SilkS")
		)
		(fp_line
			(start -0.67945 0.3048)
			(end -0.67945 -0.305054)
			(stroke
				(width 0.1)
				(type default)
			)
			(layer "F.Fab")
		)
		(fp_line
			(start -0.12065 0.3048)
			(end -0.67945 0.3048)
			(stroke
				(width 0.1)
				(type default)
			)
			(layer "F.Fab")
		)
		(fp_line
			(start 0.120396 0.3048)
			(end 0.120396 0.2794)
			(stroke
				(width 0.1)
				(type default)
			)
			(layer "F.Fab")
		)
		(fp_line
			(start 0.67945 0.3048)
			(end 0.120396 0.3048)
			(stroke
				(width 0.1)
				(type default)
			)
			(layer "F.Fab")
		)
		(fp_line
			(start -0.12065 0.2794)
			(end -0.12065 0.3048)
			(stroke
				(width 0.1)
				(type default)
			)
			(layer "F.Fab")
		)
		(fp_line
			(start 0.120396 0.2794)
			(end -0.12065 0.2794)
			(stroke
				(width 0.1)
				(type default)
			)
			(layer "F.Fab")
		)
		(fp_line
			(start -0.12065 -0.2794)
			(end 0.12065 -0.2794)
			(stroke
				(width 0.1)
				(type default)
			)
			(layer "F.Fab")
		)
		(fp_line
			(start 0.12065 -0.2794)
			(end 0.12065 -0.3048)
			(stroke
				(width 0.1)
				(type default)
			)
			(layer "F.Fab")
		)
		(fp_line
			(start 0.12065 -0.3048)
			(end 0.67945 -0.3048)
			(stroke
				(width 0.1)
				(type default)
			)
			(layer "F.Fab")
		)
		(fp_line
			(start 0.67945 -0.3048)
			(end 0.67945 0.3048)
			(stroke
				(width 0.1)
				(type default)
			)
			(layer "F.Fab")
		)
		(fp_line
			(start -0.67945 -0.305054)
			(end -0.12065 -0.305054)
			(stroke
				(width 0.1)
				(type default)
			)
			(layer "F.Fab")
		)
		(fp_line
			(start -0.12065 -0.305054)
			(end -0.12065 -0.2794)
			(stroke
				(width 0.1)
				(type default)
			)
			(layer "F.Fab")
		)
		(pad "1" smd circle
			(at -0.40005 0 270)
			(size 0 0)
			(layers "F.Cu" "F.Mask" "F.Paste")
			(net "PWRGD_P12V_MEM_CPU1")
		)
		(pad "2" smd circle
			(at 0.40005 0 270)
			(size 0 0)
			(layers "F.Cu" "F.Mask" "F.Paste")
			(net "PWRGD_P12V_MEM_CPU1_R")
		)
	)
	(footprint ""
		(layer "F.Cu")
		(at 339.696298 -332.020164 180)
		(property "Reference" "PC157"
			(at 0 0 180)
			(layer "F.SilkS")
			(hide yes)
			(effects
				(font
					(size 1.27 1.27)
				)
			)
		)
		(property "Value" ""
			(at 0 0 180)
			(layer "F.Fab")
			(effects
				(font
					(size 1.27 1.27)
				)
			)
		)
		(duplicate_pad_numbers_are_jumpers no)
		(fp_line
			(start 0.7874 0.4064)
			(end -0.7874 0.4064)
			(stroke
				(width 0.1524)
				(type default)
			)
			(layer "F.SilkS")
		)
		(fp_line
			(start 0.7874 -0.4064)
			(end 0.7874 0.4064)
			(stroke
				(width 0.1524)
				(type default)
			)
			(layer "F.SilkS")
		)
		(fp_line
			(start -0.7874 0.4064)
			(end -0.7874 -0.4064)
			(stroke
				(width 0.1524)
				(type default)
			)
			(layer "F.SilkS")
		)
		(fp_line
			(start -0.7874 -0.4064)
			(end 0.7874 -0.4064)
			(stroke
				(width 0.1524)
				(type default)
			)
			(layer "F.SilkS")
		)
		(fp_line
			(start 0.67945 0.3048)
			(end 0.120396 0.3048)
			(stroke
				(width 0.1)
				(type default)
			)
			(layer "F.Fab")
		)
		(fp_line
			(start 0.67945 -0.3048)
			(end 0.67945 0.3048)
			(stroke
				(width 0.1)
				(type default)
			)
			(layer "F.Fab")
		)
		(fp_line
			(start 0.12065 -0.2794)
			(end 0.12065 -0.3048)
			(stroke
				(width 0.1)
				(type default)
			)
			(layer "F.Fab")
		)
		(fp_line
			(start 0.12065 -0.3048)
			(end 0.67945 -0.3048)
			(stroke
				(width 0.1)
				(type default)
			)
			(layer "F.Fab")
		)
		(fp_line
			(start 0.120396 0.3048)
			(end 0.120396 0.2794)
			(stroke
				(width 0.1)
				(type default)
			)
			(layer "F.Fab")
		)
		(fp_line
			(start 0.120396 0.2794)
			(end -0.12065 0.2794)
			(stroke
				(width 0.1)
				(type default)
			)
			(layer "F.Fab")
		)
		(fp_line
			(start -0.12065 0.3048)
			(end -0.67945 0.3048)
			(stroke
				(width 0.1)
				(type default)
			)
			(layer "F.Fab")
		)
		(fp_line
			(start -0.12065 0.2794)
			(end -0.12065 0.3048)
			(stroke
				(width 0.1)
				(type default)
			)
			(layer "F.Fab")
		)
		(fp_line
			(start -0.12065 -0.2794)
			(end 0.12065 -0.2794)
			(stroke
				(width 0.1)
				(type default)
			)
			(layer "F.Fab")
		)
		(fp_line
			(start -0.12065 -0.305054)
			(end -0.12065 -0.2794)
			(stroke
				(width 0.1)
				(type default)
			)
			(layer "F.Fab")
		)
		(fp_line
			(start -0.67945 0.3048)
			(end -0.67945 -0.305054)
			(stroke
				(width 0.1)
				(type default)
			)
			(layer "F.Fab")
		)
		(fp_line
			(start -0.67945 -0.305054)
			(end -0.12065 -0.305054)
			(stroke
				(width 0.1)
				(type default)
			)
			(layer "F.Fab")
		)
		(pad "1" smd circle
			(at -0.40005 0 180)
			(size 0 0)
			(layers "F.Cu" "F.Mask" "F.Paste")
			(net "SW_PVDDCR_CPU1_P0_SW5")
		)
		(pad "2" smd circle
			(at 0.40005 0 180)
			(size 0 0)
			(layers "F.Cu" "F.Mask" "F.Paste")
			(net "SW_PVDDCR_CPU1_P0_SW5_RC")
		)
	)
)
